# T6G (Grand Teton) — schematic netlist excerpt (pin names and nets, part order shuffled) for the footprints in the layout excerpt that follows; sources: Cadence DE-HDL packaged netlist, KiCad conversion of 04192023_DAF0TMB3IC0_F0TG_MB_C_brd_V02_OCP.brd

PC551_4  Q_CAP  0.1UF 25V 10% X7R  pkg 0402  page 195 : A = SW_P12V_AUX_PVDDCR_CPU0_P0_FLT ; B = GND
R2908  Q_RES  5.11K 1% CHIP  pkg 0402LF  page 257 : A = P3V3 ; B = P3V3_ADC
R1392  Q_RES  4.7K 5% CHIP  pkg 0201LF  page 287 : A = JTAG_TCK_RT_CPU0_P1 ; B = GND

(kicad_pcb
	(version 20260206)
	(generator "pcbnew")
	(generator_version "10.0")
	(general
		(thickness 1.6)
		(legacy_teardrops no)
	)
	(paper "A4")
	(title_block
		(title "04192023_DAF0TMB3IC0_F0TG_MB_C_brd_V02_OCP.brd")
		(comment 1 "Grand Teton / footprints 3715-3717 of 8354")
	)
	(layers
		(0 "F.Cu" signal "TOP")
		(4 "In1.Cu" signal "GND")
		(6 "In2.Cu" signal "IN1")
		(8 "In3.Cu" signal "GND1")
		(10 "In4.Cu" signal "IN2")
		(12 "In5.Cu" signal "GND2")
		(14 "In6.Cu" signal "IN3")
		(16 "In7.Cu" signal "GND3")
		(18 "In8.Cu" signal "VCC")
		(20 "In9.Cu" signal "VCC1")
		(22 "In10.Cu" signal "GND4")
		(24 "In11.Cu" signal "IN4")
		(26 "In12.Cu" signal "GND5")
		(28 "In13.Cu" signal "IN5")
		(30 "In14.Cu" signal "GND6")
		(32 "In15.Cu" signal "IN6")
		(34 "In16.Cu" signal "GND7")
		(2 "B.Cu" signal "BOTTOM")
		(9 "F.Adhes" user "F.Adhesive")
		(11 "B.Adhes" user "B.Adhesive")
		(13 "F.Paste" user "Package Geometry/Pastemask Top")
		(15 "B.Paste" user "Package Geometry/Pastemask Bottom")
		(5 "F.SilkS" user "Ref Des/Silkscreen Top")
		(7 "B.SilkS" user "Ref Des/Silkscreen Bottom")
		(1 "F.Mask" user "Board Geometry/Soldermask Top")
		(3 "B.Mask" user "Board Geometry/Soldermask Bottom")
		(17 "Dwgs.User" user "User.Drawings")
		(19 "Cmts.User" user "User.Comments")
		(21 "Eco1.User" user "User.Eco1")
		(23 "Eco2.User" user "User.Eco2")
		(25 "Edge.Cuts" user "Board Geometry/Outline")
		(27 "Margin" user)
		(31 "F.CrtYd" user "Package Geometry/Place Bound Top")
		(29 "B.CrtYd" user "Package Geometry/Place Bound Bottom")
		(35 "F.Fab" user "Ref Des/Assembly Top")
		(33 "B.Fab" user "Ref Des/Assembly Bottom")
	)
	(footprint ""
		(layer "F.Cu")
		(at 329.592178 -42.176954 180)
		(property "Reference" "R2908"
			(at 0 0 180)
			(layer "F.SilkS")
			(hide yes)
			(effects
				(font
					(size 1.27 1.27)
				)
			)
		)
		(property "Value" ""
			(at 0 0 180)
			(layer "F.Fab")
			(effects
				(font
					(size 1.27 1.27)
				)
			)
		)
		(duplicate_pad_numbers_are_jumpers no)
		(fp_line
			(start 0.7874 0.4064)
			(end -0.7874 0.4064)
			(stroke
				(width 0.1524)
				(type default)
			)
			(layer "F.SilkS")
		)
		(fp_line
			(start 0.7874 -0.4064)
			(end 0.7874 0.4064)
			(stroke
				(width 0.1524)
				(type default)
			)
			(layer "F.SilkS")
		)
		(fp_line
			(start -0.7874 0.4064)
			(end -0.7874 -0.4064)
			(stroke
				(width 0.1524)
				(type default)
			)
			(layer "F.SilkS")
		)
		(fp_line
			(start -0.7874 -0.4064)
			(end 0.7874 -0.4064)
			(stroke
				(width 0.1524)
				(type default)
			)
			(layer "F.SilkS")
		)
		(fp_line
			(start 0.67945 0.3048)
			(end 0.120396 0.3048)
			(stroke
				(width 0.1)
				(type default)
			)
			(layer "F.Fab")
		)
		(fp_line
			(start 0.67945 -0.3048)
			(end 0.67945 0.3048)
			(stroke
				(width 0.1)
				(type default)
			)
			(layer "F.Fab")
		)
		(fp_line
			(start 0.12065 -0.2794)
			(end 0.12065 -0.3048)
			(stroke
				(width 0.1)
				(type default)
			)
			(layer "F.Fab")
		)
		(fp_line
			(start 0.12065 -0.3048)
			(end 0.67945 -0.3048)
			(stroke
				(width 0.1)
				(type default)
			)
			(layer "F.Fab")
		)
		(fp_line
			(start 0.120396 0.3048)
			(end 0.120396 0.2794)
			(stroke
				(width 0.1)
				(type default)
			)
			(layer "F.Fab")
		)
		(fp_line
			(start 0.120396 0.2794)
			(end -0.12065 0.2794)
			(stroke
				(width 0.1)
				(type default)
			)
			(layer "F.Fab")
		)
		(fp_line
			(start -0.12065 0.3048)
			(end -0.67945 0.3048)
			(stroke
				(width 0.1)
				(type default)
			)
			(layer "F.Fab")
		)
		(fp_line
			(start -0.12065 0.2794)
			(end -0.12065 0.3048)
			(stroke
				(width 0.1)
				(type default)
			)
			(layer "F.Fab")
		)
		(fp_line
			(start -0.12065 -0.2794)
			(end 0.12065 -0.2794)
			(stroke
				(width 0.1)
				(type default)
			)
			(layer "F.Fab")
		)
		(fp_line
			(start -0.12065 -0.305054)
			(end -0.12065 -0.2794)
			(stroke
				(width 0.1)
				(type default)
			)
			(layer "F.Fab")
		)
		(fp_line
			(start -0.67945 0.3048)
			(end -0.67945 -0.305054)
			(stroke
				(width 0.1)
				(type default)
			)
			(layer "F.Fab")
		)
		(fp_line
			(start -0.67945 -0.305054)
			(end -0.12065 -0.305054)
			(stroke
				(width 0.1)
				(type default)
			)
			(layer "F.Fab")
		)
		(pad "1" smd circle
			(at -0.40005 0 180)
			(size 0 0)
			(layers "F.Cu" "F.Mask" "F.Paste")
			(net "P3V3")
		)
		(pad "2" smd circle
			(at 0.40005 0 180)
			(size 0 0)
			(layers "F.Cu" "F.Mask" "F.Paste")
			(net "P3V3_ADC")
		)
	)
	(footprint ""
		(layer "F.Cu")
		(at 385.214114 -178.359562 180)
		(property "Reference" "PC551_4"
			(at 0 0 180)
			(layer "F.SilkS")
			(hide yes)
			(effects
				(font
					(size 1.27 1.27)
				)
			)
		)
		(property "Value" ""
			(at 0 0 180)
			(layer "F.Fab")
			(effects
				(font
					(size 1.27 1.27)
				)
			)
		)
		(duplicate_pad_numbers_are_jumpers no)
		(fp_line
			(start 0.7874 0.4064)
			(end -0.7874 0.4064)
			(stroke
				(width 0.1524)
				(type default)
			)
			(layer "F.SilkS")
		)
		(fp_line
			(start 0.7874 -0.4064)
			(end 0.7874 0.4064)
			(stroke
				(width 0.1524)
				(type default)
			)
			(layer "F.SilkS")
		)
		(fp_line
			(start -0.7874 0.4064)
			(end -0.7874 -0.4064)
			(stroke
				(width 0.1524)
				(type default)
			)
			(layer "F.SilkS")
		)
		(fp_line
			(start -0.7874 -0.4064)
			(end 0.7874 -0.4064)
			(stroke
				(width 0.1524)
				(type default)
			)
			(layer "F.SilkS")
		)
		(fp_line
			(start 0.67945 0.3048)
			(end 0.120396 0.3048)
			(stroke
				(width 0.1)
				(type default)
			)
			(layer "F.Fab")
		)
		(fp_line
			(start 0.67945 -0.3048)
			(end 0.67945 0.3048)
			(stroke
				(width 0.1)
				(type default)
			)
			(layer "F.Fab")
		)
		(fp_line
			(start 0.12065 -0.2794)
			(end 0.12065 -0.3048)
			(stroke
				(width 0.1)
				(type default)
			)
			(layer "F.Fab")
		)
		(fp_line
			(start 0.12065 -0.3048)
			(end 0.67945 -0.3048)
			(stroke
				(width 0.1)
				(type default)
			)
			(layer "F.Fab")
		)
		(fp_line
			(start 0.120396 0.3048)
			(end 0.120396 0.2794)
			(stroke
				(width 0.1)
				(type default)
			)
			(layer "F.Fab")
		)
		(fp_line
			(start 0.120396 0.2794)
			(end -0.12065 0.2794)
			(stroke
				(width 0.1)
				(type default)
			)
			(layer "F.Fab")
		)
		(fp_line
			(start -0.12065 0.3048)
			(end -0.67945 0.3048)
			(stroke
				(width 0.1)
				(type default)
			)
			(layer "F.Fab")
		)
		(fp_line
			(start -0.12065 0.2794)
			(end -0.12065 0.3048)
			(stroke
				(width 0.1)
				(type default)
			)
			(layer "F.Fab")
		)
		(fp_line
			(start -0.12065 -0.2794)
			(end 0.12065 -0.2794)
			(stroke
				(width 0.1)
				(type default)
			)
			(layer "F.Fab")
		)
		(fp_line
			(start -0.12065 -0.305054)
			(end -0.12065 -0.2794)
			(stroke
				(width 0.1)
				(type default)
			)
			(layer "F.Fab")
		)
		(fp_line
			(start -0.67945 0.3048)
			(end -0.67945 -0.305054)
			(stroke
				(width 0.1)
				(type default)
			)
			(layer "F.Fab")
		)
		(fp_line
			(start -0.67945 -0.305054)
			(end -0.12065 -0.305054)
			(stroke
				(width 0.1)
				(type default)
			)
			(layer "F.Fab")
		)
		(pad "1" smd circle
			(at -0.40005 0 180)
			(size 0 0)
			(layers "F.Cu" "F.Mask" "F.Paste")
			(net "SW_P12V_AUX_PVDDCR_CPU0_P0_FLT")
		)
		(pad "2" smd circle
			(at 0.40005 0 180)
			(size 0 0)
			(layers "F.Cu" "F.Mask" "F.Paste")
			(net "GND")
		)
	)
	(footprint ""
		(layer "F.Cu")
		(at 360.172 -401.4216)
		(property "Reference" "R1392"
			(at 0 0 0)
			(layer "F.SilkS")
			(hide yes)
			(effects
				(font
					(size 1.27 1.27)
				)
			)
		)
		(property "Value" ""
			(at 0 0 0)
			(layer "F.Fab")
			(effects
				(font
					(size 1.27 1.27)
				)
			)
		)
		(duplicate_pad_numbers_are_jumpers no)
		(fp_line
			(start -0.32512 -0.175006)
			(end 0.32512 -0.175006)
			(stroke
				(width 0.1)
				(type default)
			)
			(layer "F.Fab")
		)
		(fp_line
			(start -0.32512 0.175006)
			(end -0.32512 -0.175006)
			(stroke
				(width 0.1)
				(type default)
			)
			(layer "F.Fab")
		)
		(fp_line
			(start 0.32512 -0.175006)
			(end 0.32512 0.175006)
			(stroke
				(width 0.1)
				(type default)
			)
			(layer "F.Fab")
		)
		(fp_line
			(start 0.32512 0.175006)
			(end -0.32512 0.175006)
			(stroke
				(width 0.1)
				(type default)
			)
			(layer "F.Fab")
		)
		(pad "1" smd rect
			(at -0.2667 0)
			(size 0.3048 0.381)
			(layers "F.Cu" "F.Mask" "F.Paste")
			(net "JTAG_TCK_RT_CPU0_P1")
		)
		(pad "2" smd rect
			(at 0.2667 0 180)
			(size 0.3048 0.381)
			(layers "F.Cu" "F.Mask" "F.Paste")
			(net "GND")
		)
	)
)
